(kicad_pcb
	(version 20260206)
	(generator "pcbnew")
	(generator_version "10.0")
	(general
		(thickness 1.6)
		(legacy_teardrops no)
	)
	(paper "A4")
	(title_block
		(title "v1-chassis-manager — T6M_CM_d_v01_1031_1645.brd")
		(comment 1 "Open CloudServer (Microsoft) / footprints 1107-1113 of 2512")
	)
	(layers
		(0 "F.Cu" signal "TOP")
		(4 "In1.Cu" signal "GND1")
		(6 "In2.Cu" signal "IN1")
		(8 "In3.Cu" signal "VCC1")
		(10 "In4.Cu" signal "VCC2")
		(12 "In5.Cu" signal "GND2")
		(14 "In6.Cu" signal "IN2")
		(16 "In7.Cu" signal "IN3")
		(18 "In8.Cu" signal "GND3")
		(2 "B.Cu" signal "BOTTOM")
		(9 "F.Adhes" user "F.Adhesive")
		(11 "B.Adhes" user "B.Adhesive")
		(13 "F.Paste" user "Package Geometry/Pastemask Top")
		(15 "B.Paste" user "Package Geometry/Pastemask Bottom")
		(5 "F.SilkS" user "Ref Des/Silkscreen Top")
		(7 "B.SilkS" user "Ref Des/Silkscreen Bottom")
		(1 "F.Mask" user "Board Geometry/Soldermask Top")
		(3 "B.Mask" user "Board Geometry/Soldermask Bottom")
		(17 "Dwgs.User" user "User.Drawings")
		(19 "Cmts.User" user "User.Comments")
		(21 "Eco1.User" user "User.Eco1")
		(23 "Eco2.User" user "User.Eco2")
		(25 "Edge.Cuts" user "Board Geometry/Outline")
		(27 "Margin" user)
		(31 "F.CrtYd" user "Package Geometry/Place Bound Top")
		(29 "B.CrtYd" user "Package Geometry/Place Bound Bottom")
		(35 "F.Fab" user "Ref Des/Assembly Top")
		(33 "B.Fab" user "Ref Des/Assembly Bottom")
	)
	(footprint ""
		(layer "F.Cu")
		(at 72.957182 -6.929882 90)
		(property "Reference" "PC47"
			(at -3.90906 0.19812 90)
			(unlocked yes)
			(layer "F.SilkS")
			(effects
				(font
					(size 0.7874 0.5842)
					(thickness 0.1524)
				)
				(justify left)
			)
		)
		(property "Value" ""
			(at 0 0 90)
			(layer "F.Fab")
			(effects
				(font
					(size 1.27 1.27)
				)
			)
		)
		(duplicate_pad_numbers_are_jumpers no)
		(fp_line
			(start 0.7874 -0.4064)
			(end 0.7874 0.4064)
			(stroke
				(width 0.1524)
				(type default)
			)
			(layer "F.SilkS")
		)
		(fp_line
			(start -0.7874 -0.4064)
			(end 0.7874 -0.4064)
			(stroke
				(width 0.1524)
				(type default)
			)
			(layer "F.SilkS")
		)
		(fp_line
			(start 0 0.381)
			(end 0 -0.381)
			(stroke
				(width 0.1524)
				(type default)
			)
			(layer "F.SilkS")
		)
		(fp_line
			(start 0.7874 0.4064)
			(end -0.7874 0.4064)
			(stroke
				(width 0.1524)
				(type default)
			)
			(layer "F.SilkS")
		)
		(fp_line
			(start -0.7874 0.4064)
			(end -0.7874 -0.4064)
			(stroke
				(width 0.1524)
				(type default)
			)
			(layer "F.SilkS")
		)
		(fp_poly
			(pts
				(xy -0.5334 0.254) (xy -0.635 0.254) (xy -0.635 0.2286) (xy -0.635 -0.254) (xy -0.5334 -0.254) (xy -0.5334 -0.2794)
				(xy 0.5334 -0.2794) (xy 0.5334 -0.254) (xy 0.635 -0.254) (xy 0.635 0.254) (xy 0.5334 0.254) (xy 0.5334 0.2794)
				(xy -0.508 0.2794) (xy -0.5334 0.2794)
			)
			(stroke
				(width 0)
				(type default)
			)
			(fill no)
			(layer "F.CrtYd")
		)
		(pad "1" smd rect
			(at 0.40005 0 90)
			(size 0.4572 0.508)
			(layers "F.Cu" "F.Mask" "F.Paste")
			(net "SW_P3V3_NODE1_BT")
		)
		(pad "2" smd rect
			(at -0.40005 0 90)
			(size 0.4572 0.508)
			(layers "F.Cu" "F.Mask" "F.Paste")
			(net "SW_P3V3_NODE1_PH")
		)
	)
	(footprint ""
		(layer "F.Cu")
		(at 36.18865 -77.63256)
		(property "Reference" "C111"
			(at -3.634232 -0.321818 0)
			(unlocked yes)
			(layer "F.SilkS")
			(effects
				(font
					(size 0.7874 0.5842)
					(thickness 0.1524)
				)
			)
		)
		(property "Value" ""
			(at 0 0 0)
			(layer "F.Fab")
			(effects
				(font
					(size 1.27 1.27)
				)
			)
		)
		(duplicate_pad_numbers_are_jumpers no)
		(fp_line
			(start -1.2954 -0.5842)
			(end 1.2954 -0.5842)
			(stroke
				(width 0.1524)
				(type default)
			)
			(layer "F.SilkS")
		)
		(fp_line
			(start -1.2954 0.5842)
			(end -1.2954 -0.5842)
			(stroke
				(width 0.1524)
				(type default)
			)
			(layer "F.SilkS")
		)
		(fp_line
			(start 0 -0.5842)
			(end 0 0.5842)
			(stroke
				(width 0.1524)
				(type default)
			)
			(layer "F.SilkS")
		)
		(fp_line
			(start 1.2954 -0.5842)
			(end 1.2954 0.5842)
			(stroke
				(width 0.1524)
				(type default)
			)
			(layer "F.SilkS")
		)
		(fp_line
			(start 1.2954 0.5842)
			(end -1.2954 0.5842)
			(stroke
				(width 0.1524)
				(type default)
			)
			(layer "F.SilkS")
		)
		(fp_poly
			(pts
				(xy 0.8636 -0.4572) (xy 0.8636 -0.3556) (xy 1.143 -0.3556) (xy 1.143 0.3556) (xy 0.8636 0.3556)
				(xy 0.8636 0.4572) (xy -0.8636 0.4572) (xy -0.8636 0.3556) (xy -1.143 0.3556) (xy -1.143 -0.3556)
				(xy -0.8636 -0.3556) (xy -0.8636 -0.4572)
			)
			(stroke
				(width 0)
				(type default)
			)
			(fill no)
			(layer "F.CrtYd")
		)
		(fp_line
			(start -0.884936 -0.504952)
			(end 0.884936 -0.504952)
			(stroke
				(width 0.1)
				(type default)
			)
			(layer "F.Fab")
		)
		(fp_line
			(start -0.884936 0.504952)
			(end -0.884936 -0.504952)
			(stroke
				(width 0.1)
				(type default)
			)
			(layer "F.Fab")
		)
		(fp_line
			(start 0.884936 -0.504952)
			(end 0.884936 0.504952)
			(stroke
				(width 0.1)
				(type default)
			)
			(layer "F.Fab")
		)
		(fp_line
			(start 0.884936 0.504952)
			(end -0.884936 0.504952)
			(stroke
				(width 0.1)
				(type default)
			)
			(layer "F.Fab")
		)
		(pad "1" smd rect
			(at 0.7366 0 90)
			(size 0.7112 0.8128)
			(layers "F.Cu" "F.Mask" "F.Paste")
			(net "P1V8_VCCASFRHPLL_NODE1")
		)
		(pad "2" smd rect
			(at -0.7366 0 90)
			(size 0.7112 0.8128)
			(layers "F.Cu" "F.Mask" "F.Paste")
			(net "GND")
		)
	)
	(footprint ""
		(layer "F.Cu")
		(at 80.98663 -98.076766 90)
		(property "Reference" "Q31"
			(at 2.092452 3.293618 90)
			(unlocked yes)
			(layer "F.SilkS")
			(effects
				(font
					(size 0.7874 0.5842)
					(thickness 0.1524)
				)
			)
		)
		(property "Value" ""
			(at 0 0 90)
			(layer "F.Fab")
			(effects
				(font
					(size 1.27 1.27)
				)
			)
		)
		(duplicate_pad_numbers_are_jumpers no)
		(fp_line
			(start 2.899918 -0.525018)
			(end 2.899918 -0.345694)
			(stroke
				(width 0.1524)
				(type default)
			)
			(layer "F.SilkS")
		)
		(fp_line
			(start 1.755648 -0.525018)
			(end 2.899918 -0.525018)
			(stroke
				(width 0.1524)
				(type default)
			)
			(layer "F.SilkS")
		)
		(fp_line
			(start -0.100076 -0.525018)
			(end 1.044448 -0.525018)
			(stroke
				(width 0.1524)
				(type default)
			)
			(layer "F.SilkS")
		)
		(fp_line
			(start -0.100076 -0.320294)
			(end -0.100076 -0.525018)
			(stroke
				(width 0.1524)
				(type default)
			)
			(layer "F.SilkS")
		)
		(fp_line
			(start 2.899918 2.295906)
			(end 2.899918 2.474976)
			(stroke
				(width 0.1524)
				(type default)
			)
			(layer "F.SilkS")
		)
		(fp_line
			(start 2.899918 2.474976)
			(end 1.755648 2.474976)
			(stroke
				(width 0.1524)
				(type default)
			)
			(layer "F.SilkS")
		)
		(fp_line
			(start 1.044448 2.474976)
			(end -0.100076 2.474976)
			(stroke
				(width 0.1524)
				(type default)
			)
			(layer "F.SilkS")
		)
		(fp_line
			(start -0.100076 2.474976)
			(end -0.100076 2.295906)
			(stroke
				(width 0.1524)
				(type default)
			)
			(layer "F.SilkS")
		)
		(fp_poly
			(pts
				(xy -0.99695 0.26924) (xy -0.99695 -0.249682) (xy -0.419608 0.01397)
			)
			(stroke
				(width 0)
				(type default)
			)
			(fill yes)
			(layer "F.SilkS")
		)
		(fp_poly
			(pts
				(xy -0.100076 -0.525018) (xy -0.100076 -0.244094) (xy -0.301752 -0.244094) (xy -0.301752 2.194306)
				(xy -0.100076 2.194306) (xy -0.100076 2.474976) (xy 1.120648 2.474976) (xy 1.120648 2.651506) (xy 1.679448 2.651506)
				(xy 1.679448 2.474976) (xy 2.899918 2.474976) (xy 2.899918 2.219706) (xy 3.101848 2.219706) (xy 3.101848 -0.269494)
				(xy 2.899918 -0.269494) (xy 2.899918 -0.525018) (xy 1.679448 -0.525018) (xy 1.679448 -0.701294)
				(xy 1.120648 -0.701294) (xy 1.120648 -0.525018)
			)
			(stroke
				(width 0)
				(type default)
			)
			(fill no)
			(layer "F.CrtYd")
		)
		(fp_line
			(start 2.899918 -0.525018)
			(end 2.899918 2.474976)
			(stroke
				(width 0.1)
				(type default)
			)
			(layer "F.Fab")
		)
		(fp_line
			(start -0.100076 -0.525018)
			(end 2.899918 -0.525018)
			(stroke
				(width 0.1)
				(type default)
			)
			(layer "F.Fab")
		)
		(fp_line
			(start 2.899918 2.474976)
			(end -0.100076 2.474976)
			(stroke
				(width 0.1)
				(type default)
			)
			(layer "F.Fab")
		)
		(fp_line
			(start -0.100076 2.474976)
			(end -0.100076 -0.525018)
			(stroke
				(width 0.1)
				(type default)
			)
			(layer "F.Fab")
		)
		(pad "1" smd rect
			(at 0 0)
			(size 0.3556 0.508)
			(layers "F.Cu" "F.Mask" "F.Paste")
			(net "P3V3_SUS_NODE1")
		)
		(pad "2" smd rect
			(at 0 0.649986)
			(size 0.3556 0.508)
			(layers "F.Cu" "F.Mask" "F.Paste")
			(net "P3V3_SUS_NODE1")
		)
		(pad "3" smd rect
			(at 0 1.299972)
			(size 0.3556 0.508)
			(layers "F.Cu" "F.Mask" "F.Paste")
			(net "P3V3_SUS_NODE1")
		)
		(pad "4" smd rect
			(at 0 1.949958)
			(size 0.3556 0.508)
			(layers "F.Cu" "F.Mask" "F.Paste")
			(net "FM_CPLD_NODE1_P3V3_SUS_EN_LV")
		)
		(pad "5" smd custom
			(at 1.400048 0.975106)
			(size 0.569976 0.569976)
			(layers "F.Cu" "F.Mask" "F.Paste")
			(net "P3V3_STB_NODE1")
			(options
				(clearance outline)
				(anchor circle)
			)
			(primitives
				(gr_poly
					(pts
						(xy -1.225042 1.139952) (xy -1.225042 0.724916) (xy -1.605026 0.724916) (xy -1.605026 0.295148)
						(xy -1.225042 0.295148) (xy -1.225042 -0.839978) (xy -1.175004 -0.839978) (xy -1.175004 -1.139952)
						(xy -0.774954 -1.139952) (xy -0.774954 -0.839978) (xy -0.525018 -0.839978) (xy -0.525018 -1.139952)
						(xy -0.124968 -1.139952) (xy -0.124968 -0.839978) (xy 0.124968 -0.839978) (xy 0.124968 -1.139952)
						(xy 0.525018 -1.139952) (xy 0.525018 -0.839978) (xy 0.774954 -0.839978) (xy 0.774954 -1.139952)
						(xy 1.175004 -1.139952) (xy 1.175004 -0.839978) (xy 1.225042 -0.839978) (xy 1.225042 0.295148)
						(xy 1.605026 0.295148) (xy 1.605026 0.724916) (xy 1.225042 0.724916) (xy 1.225042 1.139952)
					)
					(width 0)
					(fill yes)
				)
			)
		)
		(zone
			(layer "F.Cu")
			(hatch none 0.5)
			(connect_pads
				(clearance 0)
			)
			(min_thickness 0.25)
			(keepout
				(tracks allowed)
				(vias not_allowed)
				(pads allowed)
				(copperpour not_allowed)
				(footprints allowed)
			)
			(placement
				(enabled no)
				(sheetname "")
			)
			(fill
				(thermal_gap 0.5)
				(thermal_bridge_width 0.5)
				(island_removal_mode 0)
			)
			(polygon
				(pts
					(xy 80.463136 -98.791014) (xy 83.460336 -98.791014) (xy 83.460336 -98.410014) (xy 80.463136 -98.410014)
				)
			)
		)
		(zone
			(layer "F.Cu")
			(hatch none 0.5)
			(connect_pads
				(clearance 0)
			)
			(min_thickness 0.25)
			(keepout
				(tracks not_allowed)
				(vias allowed)
				(pads allowed)
				(copperpour not_allowed)
				(footprints allowed)
			)
			(placement
				(enabled no)
				(sheetname "")
			)
			(fill
				(thermal_gap 0.5)
				(thermal_bridge_width 0.5)
				(island_removal_mode 0)
			)
			(polygon
				(pts
					(xy 80.463136 -98.410014) (xy 83.460336 -98.410014) (xy 83.460336 -98.791014) (xy 80.463136 -98.791014)
				)
			)
		)
	)
	(footprint ""
		(layer "F.Cu")
		(at 64.193166 -96.709992 -90)
		(property "Reference" "R58"
			(at 54.98719 -28.497276 90)
			(unlocked yes)
			(layer "F.SilkS")
			(effects
				(font
					(size 0.7874 0.5842)
					(thickness 0.1524)
				)
				(justify left)
			)
		)
		(property "Value" ""
			(at 0 0 270)
			(layer "F.Fab")
			(effects
				(font
					(size 1.27 1.27)
				)
			)
		)
		(duplicate_pad_numbers_are_jumpers no)
		(fp_line
			(start -0.7874 0.4064)
			(end -0.7874 -0.4064)
			(stroke
				(width 0.1524)
				(type default)
			)
			(layer "F.SilkS")
		)
		(fp_line
			(start 0.7874 0.4064)
			(end -0.7874 0.4064)
			(stroke
				(width 0.1524)
				(type default)
			)
			(layer "F.SilkS")
		)
		(fp_line
			(start -0.7874 -0.4064)
			(end 0.7874 -0.4064)
			(stroke
				(width 0.1524)
				(type default)
			)
			(layer "F.SilkS")
		)
		(fp_line
			(start 0.7874 -0.4064)
			(end 0.7874 0.4064)
			(stroke
				(width 0.1524)
				(type default)
			)
			(layer "F.SilkS")
		)
		(fp_poly
			(pts
				(xy -0.508 0.2794) (xy -0.508 0.2286) (xy -0.635 0.2286) (xy -0.635 -0.254) (xy -0.5334 -0.254)
				(xy -0.5334 -0.2794) (xy 0.5334 -0.2794) (xy 0.5334 -0.254) (xy 0.635 -0.254) (xy 0.635 0.254) (xy 0.5334 0.254)
				(xy 0.5334 0.2794)
			)
			(stroke
				(width 0)
				(type default)
			)
			(fill no)
			(layer "F.CrtYd")
		)
		(pad "1" smd rect
			(at 0.40005 0 270)
			(size 0.4572 0.508)
			(layers "F.Cu" "F.Mask" "F.Paste")
			(net "SPI_CPU_NODE1_MOSI_R")
		)
		(pad "2" smd rect
			(at -0.40005 0 270)
			(size 0.4572 0.508)
			(layers "F.Cu" "F.Mask" "F.Paste")
			(net "SPI_CPU_NODE1_MOSI")
		)
	)
	(footprint ""
		(layer "F.Cu")
		(at 35.766502 -83.294982)
		(property "Reference" "R107"
			(at -4.685284 0.049784 0)
			(unlocked yes)
			(layer "F.SilkS")
			(effects
				(font
					(size 0.7874 0.5842)
					(thickness 0.1524)
				)
				(justify left)
			)
		)
		(property "Value" ""
			(at 0 0 0)
			(layer "F.Fab")
			(effects
				(font
					(size 1.27 1.27)
				)
			)
		)
		(duplicate_pad_numbers_are_jumpers no)
		(fp_line
			(start -0.7874 -0.4064)
			(end 0.7874 -0.4064)
			(stroke
				(width 0.1524)
				(type default)
			)
			(layer "F.SilkS")
		)
		(fp_line
			(start -0.7874 0.4064)
			(end -0.7874 -0.4064)
			(stroke
				(width 0.1524)
				(type default)
			)
			(layer "F.SilkS")
		)
		(fp_line
			(start 0.7874 -0.4064)
			(end 0.7874 0.4064)
			(stroke
				(width 0.1524)
				(type default)
			)
			(layer "F.SilkS")
		)
		(fp_line
			(start 0.7874 0.4064)
			(end -0.7874 0.4064)
			(stroke
				(width 0.1524)
				(type default)
			)
			(layer "F.SilkS")
		)
		(fp_poly
			(pts
				(xy -0.508 0.2794) (xy -0.508 0.2286) (xy -0.635 0.2286) (xy -0.635 -0.254) (xy -0.5334 -0.254)
				(xy -0.5334 -0.2794) (xy 0.5334 -0.2794) (xy 0.5334 -0.254) (xy 0.635 -0.254) (xy 0.635 0.254) (xy 0.5334 0.254)
				(xy 0.5334 0.2794)
			)
			(stroke
				(width 0)
				(type default)
			)
			(fill no)
			(layer "F.CrtYd")
		)
		(pad "1" smd rect
			(at 0.40005 0)
			(size 0.4572 0.508)
			(layers "F.Cu" "F.Mask" "F.Paste")
			(net "PD_NODE1_NTB_PERP")
		)
		(pad "2" smd rect
			(at -0.40005 0)
			(size 0.4572 0.508)
			(layers "F.Cu" "F.Mask" "F.Paste")
			(net "GND")
		)
	)
	(footprint ""
		(layer "F.Cu")
		(at 149.33676 -185.205624 90)
		(property "Reference" "C750"
			(at 4.768088 0.250952 90)
			(unlocked yes)
			(layer "F.SilkS")
			(effects
				(font
					(size 0.7874 0.5842)
					(thickness 0.1524)
				)
				(justify left)
			)
		)
		(property "Value" ""
			(at 0 0 90)
			(layer "F.Fab")
			(effects
				(font
					(size 1.27 1.27)
				)
			)
		)
		(duplicate_pad_numbers_are_jumpers no)
		(fp_line
			(start 0.7874 -0.4064)
			(end 0.7874 0.4064)
			(stroke
				(width 0.1524)
				(type default)
			)
			(layer "F.SilkS")
		)
		(fp_line
			(start -0.7874 -0.4064)
			(end 0.7874 -0.4064)
			(stroke
				(width 0.1524)
				(type default)
			)
			(layer "F.SilkS")
		)
		(fp_line
			(start 0 0.381)
			(end 0 -0.381)
			(stroke
				(width 0.1524)
				(type default)
			)
			(layer "F.SilkS")
		)
		(fp_line
			(start 0.7874 0.4064)
			(end -0.7874 0.4064)
			(stroke
				(width 0.1524)
				(type default)
			)
			(layer "F.SilkS")
		)
		(fp_line
			(start -0.7874 0.4064)
			(end -0.7874 -0.4064)
			(stroke
				(width 0.1524)
				(type default)
			)
			(layer "F.SilkS")
		)
		(fp_poly
			(pts
				(xy -0.5334 0.254) (xy -0.635 0.254) (xy -0.635 0.2286) (xy -0.635 -0.254) (xy -0.5334 -0.254) (xy -0.5334 -0.2794)
				(xy 0.5334 -0.2794) (xy 0.5334 -0.254) (xy 0.635 -0.254) (xy 0.635 0.254) (xy 0.5334 0.254) (xy 0.5334 0.2794)
				(xy -0.508 0.2794) (xy -0.5334 0.2794)
			)
			(stroke
				(width 0)
				(type default)
			)
			(fill no)
			(layer "F.CrtYd")
		)
		(pad "1" smd rect
			(at 0.40005 0 90)
			(size 0.4572 0.508)
			(layers "F.Cu" "F.Mask" "F.Paste")
			(net "UART_T12_NODE2_RXD")
		)
		(pad "2" smd rect
			(at -0.40005 0 90)
			(size 0.4572 0.508)
			(layers "F.Cu" "F.Mask" "F.Paste")
			(net "GND")
		)
	)
	(footprint ""
		(layer "F.Cu")
		(at 138.922252 -154.79395 90)
		(property "Reference" "R279"
			(at -110.714282 -61.383926 90)
			(unlocked yes)
			(layer "F.SilkS")
			(effects
				(font
					(size 0.7874 0.5842)
					(thickness 0.1524)
				)
				(justify left)
			)
		)
		(property "Value" ""
			(at 0 0 90)
			(layer "F.Fab")
			(effects
				(font
					(size 1.27 1.27)
				)
			)
		)
		(duplicate_pad_numbers_are_jumpers no)
		(fp_line
			(start 0.7874 -0.4064)
			(end 0.7874 0.4064)
			(stroke
				(width 0.1524)
				(type default)
			)
			(layer "F.SilkS")
		)
		(fp_line
			(start -0.7874 -0.4064)
			(end 0.7874 -0.4064)
			(stroke
				(width 0.1524)
				(type default)
			)
			(layer "F.SilkS")
		)
		(fp_line
			(start 0.7874 0.4064)
			(end -0.7874 0.4064)
			(stroke
				(width 0.1524)
				(type default)
			)
			(layer "F.SilkS")
		)
		(fp_line
			(start -0.7874 0.4064)
			(end -0.7874 -0.4064)
			(stroke
				(width 0.1524)
				(type default)
			)
			(layer "F.SilkS")
		)
		(fp_poly
			(pts
				(xy -0.508 0.2794) (xy -0.508 0.2286) (xy -0.635 0.2286) (xy -0.635 -0.254) (xy -0.5334 -0.254)
				(xy -0.5334 -0.2794) (xy 0.5334 -0.2794) (xy 0.5334 -0.254) (xy 0.635 -0.254) (xy 0.635 0.254) (xy 0.5334 0.254)
				(xy 0.5334 0.2794)
			)
			(stroke
				(width 0)
				(type default)
			)
			(fill no)
			(layer "F.CrtYd")
		)
		(pad "1" smd rect
			(at 0.40005 0 90)
			(size 0.4572 0.508)
			(layers "F.Cu" "F.Mask" "F.Paste")
			(net "GND")
		)
		(pad "2" smd rect
			(at -0.40005 0 90)
			(size 0.4572 0.508)
			(layers "F.Cu" "F.Mask" "F.Paste")
			(net "PCIE_SW_P2_CTCDIS")
		)
	)
)
